# T6G (Grand Teton) — schematic netlist excerpt (pin names and nets, part order shuffled) for the footprints in the layout excerpt that follows; sources: Cadence DE-HDL packaged netlist, KiCad conversion of 04192023_DAF0TMB3IC0_F0TG_MB_C_brd_V02_OCP.brd

PR4525  Q_RES  10M 1% CHIP  pkg 0402LF  page 134 : A = P3V3_OCP_SFF_R ; B = P3V3_OCP_GATE_PU202_1
C82  Q_CAP  10UF 6.3V 20% X6S  pkg C0402  page 183 : A = P3V3_9ZXL045_P1_VDDA ; B = GND

(kicad_pcb
	(version 20260206)
	(generator "pcbnew")
	(generator_version "10.0")
	(general
		(thickness 1.6)
		(legacy_teardrops no)
	)
	(paper "A4")
	(title_block
		(title "04192023_DAF0TMB3IC0_F0TG_MB_C_brd_V02_OCP.brd")
		(comment 1 "Grand Teton / footprints 2588-2589 of 8354")
	)
	(layers
		(0 "F.Cu" signal "TOP")
		(4 "In1.Cu" signal "GND")
		(6 "In2.Cu" signal "IN1")
		(8 "In3.Cu" signal "GND1")
		(10 "In4.Cu" signal "IN2")
		(12 "In5.Cu" signal "GND2")
		(14 "In6.Cu" signal "IN3")
		(16 "In7.Cu" signal "GND3")
		(18 "In8.Cu" signal "VCC")
		(20 "In9.Cu" signal "VCC1")
		(22 "In10.Cu" signal "GND4")
		(24 "In11.Cu" signal "IN4")
		(26 "In12.Cu" signal "GND5")
		(28 "In13.Cu" signal "IN5")
		(30 "In14.Cu" signal "GND6")
		(32 "In15.Cu" signal "IN6")
		(34 "In16.Cu" signal "GND7")
		(2 "B.Cu" signal "BOTTOM")
		(9 "F.Adhes" user "F.Adhesive")
		(11 "B.Adhes" user "B.Adhesive")
		(13 "F.Paste" user "Package Geometry/Pastemask Top")
		(15 "B.Paste" user "Package Geometry/Pastemask Bottom")
		(5 "F.SilkS" user "Ref Des/Silkscreen Top")
		(7 "B.SilkS" user "Ref Des/Silkscreen Bottom")
		(1 "F.Mask" user "Board Geometry/Soldermask Top")
		(3 "B.Mask" user "Board Geometry/Soldermask Bottom")
		(17 "Dwgs.User" user "User.Drawings")
		(19 "Cmts.User" user "User.Comments")
		(21 "Eco1.User" user "User.Eco1")
		(23 "Eco2.User" user "User.Eco2")
		(25 "Edge.Cuts" user "Board Geometry/Outline")
		(27 "Margin" user)
		(31 "F.CrtYd" user "Package Geometry/Place Bound Top")
		(29 "B.CrtYd" user "Package Geometry/Place Bound Bottom")
		(35 "F.Fab" user "Ref Des/Assembly Top")
		(33 "B.Fab" user "Ref Des/Assembly Bottom")
	)
	(footprint ""
		(layer "F.Cu")
		(at 112.649 -412.1658)
		(property "Reference" "C82"
			(at 0 0 0)
			(layer "F.SilkS")
			(hide yes)
			(effects
				(font
					(size 1.27 1.27)
				)
			)
		)
		(property "Value" ""
			(at 0 0 0)
			(layer "F.Fab")
			(effects
				(font
					(size 1.27 1.27)
				)
			)
		)
		(duplicate_pad_numbers_are_jumpers no)
		(fp_line
			(start -0.7874 -0.4064)
			(end 0.7874 -0.4064)
			(stroke
				(width 0.1524)
				(type default)
			)
			(layer "F.SilkS")
		)
		(fp_line
			(start -0.7874 0.4064)
			(end -0.7874 -0.4064)
			(stroke
				(width 0.1524)
				(type default)
			)
			(layer "F.SilkS")
		)
		(fp_line
			(start 0.7874 -0.4064)
			(end 0.7874 0.4064)
			(stroke
				(width 0.1524)
				(type default)
			)
			(layer "F.SilkS")
		)
		(fp_line
			(start 0.7874 0.4064)
			(end -0.7874 0.4064)
			(stroke
				(width 0.1524)
				(type default)
			)
			(layer "F.SilkS")
		)
		(fp_line
			(start -0.67945 -0.305054)
			(end -0.12065 -0.305054)
			(stroke
				(width 0.1)
				(type default)
			)
			(layer "F.Fab")
		)
		(fp_line
			(start -0.67945 0.3048)
			(end -0.67945 -0.305054)
			(stroke
				(width 0.1)
				(type default)
			)
			(layer "F.Fab")
		)
		(fp_line
			(start -0.12065 -0.305054)
			(end -0.12065 -0.2794)
			(stroke
				(width 0.1)
				(type default)
			)
			(layer "F.Fab")
		)
		(fp_line
			(start -0.12065 -0.2794)
			(end 0.12065 -0.2794)
			(stroke
				(width 0.1)
				(type default)
			)
			(layer "F.Fab")
		)
		(fp_line
			(start -0.12065 0.2794)
			(end -0.12065 0.3048)
			(stroke
				(width 0.1)
				(type default)
			)
			(layer "F.Fab")
		)
		(fp_line
			(start -0.12065 0.3048)
			(end -0.67945 0.3048)
			(stroke
				(width 0.1)
				(type default)
			)
			(layer "F.Fab")
		)
		(fp_line
			(start 0.120396 0.2794)
			(end -0.12065 0.2794)
			(stroke
				(width 0.1)
				(type default)
			)
			(layer "F.Fab")
		)
		(fp_line
			(start 0.120396 0.3048)
			(end 0.120396 0.2794)
			(stroke
				(width 0.1)
				(type default)
			)
			(layer "F.Fab")
		)
		(fp_line
			(start 0.12065 -0.3048)
			(end 0.67945 -0.3048)
			(stroke
				(width 0.1)
				(type default)
			)
			(layer "F.Fab")
		)
		(fp_line
			(start 0.12065 -0.2794)
			(end 0.12065 -0.3048)
			(stroke
				(width 0.1)
				(type default)
			)
			(layer "F.Fab")
		)
		(fp_line
			(start 0.67945 -0.3048)
			(end 0.67945 0.3048)
			(stroke
				(width 0.1)
				(type default)
			)
			(layer "F.Fab")
		)
		(fp_line
			(start 0.67945 0.3048)
			(end 0.120396 0.3048)
			(stroke
				(width 0.1)
				(type default)
			)
			(layer "F.Fab")
		)
		(pad "1" smd circle
			(at -0.40005 0)
			(size 0 0)
			(layers "F.Cu" "F.Mask" "F.Paste")
			(net "P3V3_9ZXL045_P1_VDDA")
		)
		(pad "2" smd circle
			(at 0.40005 0)
			(size 0 0)
			(layers "F.Cu" "F.Mask" "F.Paste")
			(net "GND")
		)
	)
	(footprint ""
		(layer "F.Cu")
		(at 436.608474 -103.768398 90)
		(property "Reference" "PR4525"
			(at 0 0 90)
			(layer "F.SilkS")
			(hide yes)
			(effects
				(font
					(size 1.27 1.27)
				)
			)
		)
		(property "Value" ""
			(at 0 0 90)
			(layer "F.Fab")
			(effects
				(font
					(size 1.27 1.27)
				)
			)
		)
		(duplicate_pad_numbers_are_jumpers no)
		(fp_line
			(start 0.7874 -0.4064)
			(end 0.7874 0.4064)
			(stroke
				(width 0.1524)
				(type default)
			)
			(layer "F.SilkS")
		)
		(fp_line
			(start -0.7874 -0.4064)
			(end 0.7874 -0.4064)
			(stroke
				(width 0.1524)
				(type default)
			)
			(layer "F.SilkS")
		)
		(fp_line
			(start 0.7874 0.4064)
			(end -0.7874 0.4064)
			(stroke
				(width 0.1524)
				(type default)
			)
			(layer "F.SilkS")
		)
		(fp_line
			(start -0.7874 0.4064)
			(end -0.7874 -0.4064)
			(stroke
				(width 0.1524)
				(type default)
			)
			(layer "F.SilkS")
		)
		(fp_line
			(start -0.12065 -0.305054)
			(end -0.12065 -0.2794)
			(stroke
				(width 0.1)
				(type default)
			)
			(layer "F.Fab")
		)
		(fp_line
			(start -0.67945 -0.305054)
			(end -0.12065 -0.305054)
			(stroke
				(width 0.1)
				(type default)
			)
			(layer "F.Fab")
		)
		(fp_line
			(start 0.67945 -0.3048)
			(end 0.67945 0.3048)
			(stroke
				(width 0.1)
				(type default)
			)
			(layer "F.Fab")
		)
		(fp_line
			(start 0.12065 -0.3048)
			(end 0.67945 -0.3048)
			(stroke
				(width 0.1)
				(type default)
			)
			(layer "F.Fab")
		)
		(fp_line
			(start 0.12065 -0.2794)
			(end 0.12065 -0.3048)
			(stroke
				(width 0.1)
				(type default)
			)
			(layer "F.Fab")
		)
		(fp_line
			(start -0.12065 -0.2794)
			(end 0.12065 -0.2794)
			(stroke
				(width 0.1)
				(type default)
			)
			(layer "F.Fab")
		)
		(fp_line
			(start 0.120396 0.2794)
			(end -0.12065 0.2794)
			(stroke
				(width 0.1)
				(type default)
			)
			(layer "F.Fab")
		)
		(fp_line
			(start -0.12065 0.2794)
			(end -0.12065 0.3048)
			(stroke
				(width 0.1)
				(type default)
			)
			(layer "F.Fab")
		)
		(fp_line
			(start 0.67945 0.3048)
			(end 0.120396 0.3048)
			(stroke
				(width 0.1)
				(type default)
			)
			(layer "F.Fab")
		)
		(fp_line
			(start 0.120396 0.3048)
			(end 0.120396 0.2794)
			(stroke
				(width 0.1)
				(type default)
			)
			(layer "F.Fab")
		)
		(fp_line
			(start -0.12065 0.3048)
			(end -0.67945 0.3048)
			(stroke
				(width 0.1)
				(type default)
			)
			(layer "F.Fab")
		)
		(fp_line
			(start -0.67945 0.3048)
			(end -0.67945 -0.305054)
			(stroke
				(width 0.1)
				(type default)
			)
			(layer "F.Fab")
		)
		(pad "1" smd circle
			(at -0.40005 0 90)
			(size 0 0)
			(layers "F.Cu" "F.Mask" "F.Paste")
			(net "P3V3_OCP_SFF_R")
		)
		(pad "2" smd circle
			(at 0.40005 0 90)
			(size 0 0)
			(layers "F.Cu" "F.Mask" "F.Paste")
			(net "P3V3_OCP_GATE_PU202_1")
		)
	)
)
